# T6G (Grand Teton) — schematic netlist excerpt (pin names and nets, part order shuffled) for the footprints in the layout excerpt that follows; sources: Cadence DE-HDL packaged netlist, KiCad conversion of 04192023_DAF0TMB3IC0_F0TG_MB_C_brd_V02_OCP.brd

C840  Q_CAP_DIFFBUS  DIFF BUS_0.22UF 6.3V 20% X6S  pkg C0201  page 64 : \1\ = P5E_CPU0_P2_TX_C_DN<14> ; \2\ = P5E_CPU0_P2_TX_DN<14>
R3391  Q_RES  49.9 1% CHIP  pkg 0402LF  page 128 : A = RST_PERST_2_SWB_BUF_R_N ; B = RST_PERST_2_SWB_BUF_N

(kicad_pcb
	(version 20260206)
	(generator "pcbnew")
	(generator_version "10.0")
	(general
		(thickness 1.6)
		(legacy_teardrops no)
	)
	(paper "A4")
	(title_block
		(title "04192023_DAF0TMB3IC0_F0TG_MB_C_brd_V02_OCP.brd")
		(comment 1 "Grand Teton / footprints 2026-2027 of 8354")
	)
	(layers
		(0 "F.Cu" signal "TOP")
		(4 "In1.Cu" signal "GND")
		(6 "In2.Cu" signal "IN1")
		(8 "In3.Cu" signal "GND1")
		(10 "In4.Cu" signal "IN2")
		(12 "In5.Cu" signal "GND2")
		(14 "In6.Cu" signal "IN3")
		(16 "In7.Cu" signal "GND3")
		(18 "In8.Cu" signal "VCC")
		(20 "In9.Cu" signal "VCC1")
		(22 "In10.Cu" signal "GND4")
		(24 "In11.Cu" signal "IN4")
		(26 "In12.Cu" signal "GND5")
		(28 "In13.Cu" signal "IN5")
		(30 "In14.Cu" signal "GND6")
		(32 "In15.Cu" signal "IN6")
		(34 "In16.Cu" signal "GND7")
		(2 "B.Cu" signal "BOTTOM")
		(9 "F.Adhes" user "F.Adhesive")
		(11 "B.Adhes" user "B.Adhesive")
		(13 "F.Paste" user "Package Geometry/Pastemask Top")
		(15 "B.Paste" user "Package Geometry/Pastemask Bottom")
		(5 "F.SilkS" user "Ref Des/Silkscreen Top")
		(7 "B.SilkS" user "Ref Des/Silkscreen Bottom")
		(1 "F.Mask" user "Board Geometry/Soldermask Top")
		(3 "B.Mask" user "Board Geometry/Soldermask Bottom")
		(17 "Dwgs.User" user "User.Drawings")
		(19 "Cmts.User" user "User.Comments")
		(21 "Eco1.User" user "User.Eco1")
		(23 "Eco2.User" user "User.Eco2")
		(25 "Edge.Cuts" user "Board Geometry/Outline")
		(27 "Margin" user)
		(31 "F.CrtYd" user "Package Geometry/Place Bound Top")
		(29 "B.CrtYd" user "Package Geometry/Place Bound Bottom")
		(35 "F.Fab" user "Ref Des/Assembly Top")
		(33 "B.Fab" user "Ref Des/Assembly Bottom")
	)
	(footprint ""
		(layer "F.Cu")
		(at 52.705 -433.578)
		(property "Reference" "R3391"
			(at 0 0 0)
			(layer "F.SilkS")
			(hide yes)
			(effects
				(font
					(size 1.27 1.27)
				)
			)
		)
		(property "Value" ""
			(at 0 0 0)
			(layer "F.Fab")
			(effects
				(font
					(size 1.27 1.27)
				)
			)
		)
		(duplicate_pad_numbers_are_jumpers no)
		(fp_line
			(start -0.7874 -0.4064)
			(end 0.7874 -0.4064)
			(stroke
				(width 0.1524)
				(type default)
			)
			(layer "F.SilkS")
		)
		(fp_line
			(start -0.7874 0.4064)
			(end -0.7874 -0.4064)
			(stroke
				(width 0.1524)
				(type default)
			)
			(layer "F.SilkS")
		)
		(fp_line
			(start 0.7874 -0.4064)
			(end 0.7874 0.4064)
			(stroke
				(width 0.1524)
				(type default)
			)
			(layer "F.SilkS")
		)
		(fp_line
			(start 0.7874 0.4064)
			(end -0.7874 0.4064)
			(stroke
				(width 0.1524)
				(type default)
			)
			(layer "F.SilkS")
		)
		(fp_line
			(start -0.67945 -0.305054)
			(end -0.12065 -0.305054)
			(stroke
				(width 0.1)
				(type default)
			)
			(layer "F.Fab")
		)
		(fp_line
			(start -0.67945 0.3048)
			(end -0.67945 -0.305054)
			(stroke
				(width 0.1)
				(type default)
			)
			(layer "F.Fab")
		)
		(fp_line
			(start -0.12065 -0.305054)
			(end -0.12065 -0.2794)
			(stroke
				(width 0.1)
				(type default)
			)
			(layer "F.Fab")
		)
		(fp_line
			(start -0.12065 -0.2794)
			(end 0.12065 -0.2794)
			(stroke
				(width 0.1)
				(type default)
			)
			(layer "F.Fab")
		)
		(fp_line
			(start -0.12065 0.2794)
			(end -0.12065 0.3048)
			(stroke
				(width 0.1)
				(type default)
			)
			(layer "F.Fab")
		)
		(fp_line
			(start -0.12065 0.3048)
			(end -0.67945 0.3048)
			(stroke
				(width 0.1)
				(type default)
			)
			(layer "F.Fab")
		)
		(fp_line
			(start 0.120396 0.2794)
			(end -0.12065 0.2794)
			(stroke
				(width 0.1)
				(type default)
			)
			(layer "F.Fab")
		)
		(fp_line
			(start 0.120396 0.3048)
			(end 0.120396 0.2794)
			(stroke
				(width 0.1)
				(type default)
			)
			(layer "F.Fab")
		)
		(fp_line
			(start 0.12065 -0.3048)
			(end 0.67945 -0.3048)
			(stroke
				(width 0.1)
				(type default)
			)
			(layer "F.Fab")
		)
		(fp_line
			(start 0.12065 -0.2794)
			(end 0.12065 -0.3048)
			(stroke
				(width 0.1)
				(type default)
			)
			(layer "F.Fab")
		)
		(fp_line
			(start 0.67945 -0.3048)
			(end 0.67945 0.3048)
			(stroke
				(width 0.1)
				(type default)
			)
			(layer "F.Fab")
		)
		(fp_line
			(start 0.67945 0.3048)
			(end 0.120396 0.3048)
			(stroke
				(width 0.1)
				(type default)
			)
			(layer "F.Fab")
		)
		(pad "1" smd circle
			(at -0.40005 0)
			(size 0 0)
			(layers "F.Cu" "F.Mask" "F.Paste")
			(net "RST_PERST_2_SWB_BUF_R_N")
		)
		(pad "2" smd circle
			(at 0.40005 0)
			(size 0 0)
			(layers "F.Cu" "F.Mask" "F.Paste")
			(net "RST_PERST_2_SWB_BUF_N")
		)
	)
	(footprint ""
		(layer "F.Cu")
		(at 425.36872 -385.364228)
		(property "Reference" "C840"
			(at 0 0 0)
			(layer "F.SilkS")
			(hide yes)
			(effects
				(font
					(size 1.27 1.27)
				)
			)
		)
		(property "Value" ""
			(at 0 0 0)
			(layer "F.Fab")
			(effects
				(font
					(size 1.27 1.27)
				)
			)
		)
		(duplicate_pad_numbers_are_jumpers no)
		(fp_line
			(start -0.299974 -0.150114)
			(end 0.299974 -0.150114)
			(stroke
				(width 0.1)
				(type default)
			)
			(layer "F.Fab")
		)
		(fp_line
			(start -0.299974 0.150114)
			(end -0.299974 -0.150114)
			(stroke
				(width 0.1)
				(type default)
			)
			(layer "F.Fab")
		)
		(fp_line
			(start 0.299974 -0.150114)
			(end 0.299974 0.150114)
			(stroke
				(width 0.1)
				(type default)
			)
			(layer "F.Fab")
		)
		(fp_line
			(start 0.299974 0.150114)
			(end -0.299974 0.150114)
			(stroke
				(width 0.1)
				(type default)
			)
			(layer "F.Fab")
		)
		(pad "1" smd rect
			(at -0.2667 0)
			(size 0.3048 0.381)
			(layers "F.Cu" "F.Mask" "F.Paste")
			(net "P5E_CPU0_P2_TX_C_DN<14>")
		)
		(pad "2" smd rect
			(at 0.2667 0)
			(size 0.3048 0.381)
			(layers "F.Cu" "F.Mask" "F.Paste")
			(net "P5E_CPU0_P2_TX_DN<14>")
		)
	)
)
